(kicad_pcb
	(version 20260206)
	(generator "pcbnew")
	(generator_version "10.0")
	(general
		(thickness 1.6)
		(legacy_teardrops no)
	)
	(paper "A4")
	(title_block
		(title "01162023_DA0F0TEBIF0_F0T_Expander_BD_F_brd_V02_OCP.brd")
		(comment 1 "Grand Teton / footprints 1987-1994 of 9728")
	)
	(layers
		(0 "F.Cu" signal "TOP")
		(4 "In1.Cu" signal "GND")
		(6 "In2.Cu" signal "VCC")
		(8 "In3.Cu" signal "VCC1")
		(10 "In4.Cu" signal "GND1")
		(12 "In5.Cu" signal "IN1")
		(14 "In6.Cu" signal "GND2")
		(16 "In7.Cu" signal "IN2")
		(18 "In8.Cu" signal "GND3")
		(20 "In9.Cu" signal "IN3")
		(22 "In10.Cu" signal "GND4")
		(24 "In11.Cu" signal "IN4")
		(26 "In12.Cu" signal "GND5")
		(28 "In13.Cu" signal "IN5")
		(30 "In14.Cu" signal "GND6")
		(32 "In15.Cu" signal "IN6")
		(34 "In16.Cu" signal "GND7")
		(2 "B.Cu" signal "BOTTOM")
		(9 "F.Adhes" user "F.Adhesive")
		(11 "B.Adhes" user "B.Adhesive")
		(13 "F.Paste" user "Package Geometry/Pastemask Top")
		(15 "B.Paste" user "Package Geometry/Pastemask Bottom")
		(5 "F.SilkS" user "Ref Des/Silkscreen Top")
		(7 "B.SilkS" user "Ref Des/Silkscreen Bottom")
		(1 "F.Mask" user "Board Geometry/Soldermask Top")
		(3 "B.Mask" user "Board Geometry/Soldermask Bottom")
		(17 "Dwgs.User" user "User.Drawings")
		(19 "Cmts.User" user "User.Comments")
		(21 "Eco1.User" user "User.Eco1")
		(23 "Eco2.User" user "User.Eco2")
		(25 "Edge.Cuts" user "Board Geometry/Outline")
		(27 "Margin" user)
		(31 "F.CrtYd" user "Package Geometry/Place Bound Top")
		(29 "B.CrtYd" user "Package Geometry/Place Bound Bottom")
		(35 "F.Fab" user "Ref Des/Assembly Top")
		(33 "B.Fab" user "Ref Des/Assembly Bottom")
	)
	(footprint ""
		(layer "F.Cu")
		(at 265.46683 -208.039462 90)
		(property "Reference" "D24"
			(at -0.623062 -1.66116 90)
			(unlocked yes)
			(layer "F.SilkS")
			(effects
				(font
					(size 0.7874 0.5842)
					(thickness 0.1524)
				)
				(justify left)
			)
		)
		(property "Value" ""
			(at 0 0 90)
			(layer "F.Fab")
			(effects
				(font
					(size 1.27 1.27)
				)
			)
		)
		(duplicate_pad_numbers_are_jumpers no)
		(fp_line
			(start 2.7178 -1.0414)
			(end 2.7178 1.0414)
			(stroke
				(width 0.1524)
				(type default)
			)
			(layer "F.SilkS")
		)
		(fp_line
			(start 2.5908 -1.0414)
			(end 2.5908 1.0414)
			(stroke
				(width 0.1524)
				(type default)
			)
			(layer "F.SilkS")
		)
		(fp_line
			(start 2.4638 -1.0414)
			(end 2.4638 1.0414)
			(stroke
				(width 0.1524)
				(type default)
			)
			(layer "F.SilkS")
		)
		(fp_line
			(start -2.4638 -1.0414)
			(end 2.7178 -1.0414)
			(stroke
				(width 0.1524)
				(type default)
			)
			(layer "F.SilkS")
		)
		(fp_line
			(start 0.254 -0.508)
			(end 0.254 0.5334)
			(stroke
				(width 0.1524)
				(type default)
			)
			(layer "F.SilkS")
		)
		(fp_line
			(start -0.508 -0.508)
			(end -0.508 0.5334)
			(stroke
				(width 0.1524)
				(type default)
			)
			(layer "F.SilkS")
		)
		(fp_line
			(start 0.1778 -0.0254)
			(end -0.4826 -0.4826)
			(stroke
				(width 0.1524)
				(type default)
			)
			(layer "F.SilkS")
		)
		(fp_line
			(start -0.508 0.5334)
			(end 0.1778 -0.0254)
			(stroke
				(width 0.1524)
				(type default)
			)
			(layer "F.SilkS")
		)
		(fp_line
			(start 2.7178 1.0414)
			(end -2.4638 1.0414)
			(stroke
				(width 0.1524)
				(type default)
			)
			(layer "F.SilkS")
		)
		(fp_line
			(start -2.4638 1.0414)
			(end -2.4638 -1.0414)
			(stroke
				(width 0.1524)
				(type default)
			)
			(layer "F.SilkS")
		)
		(fp_line
			(start 2.7178 -1.0414)
			(end 2.7178 1.0414)
			(stroke
				(width 0.1)
				(type default)
			)
			(layer "F.Fab")
		)
		(fp_line
			(start -2.4638 -1.0414)
			(end 2.7178 -1.0414)
			(stroke
				(width 0.1)
				(type default)
			)
			(layer "F.Fab")
		)
		(fp_line
			(start 2.7178 1.0414)
			(end -2.4638 1.0414)
			(stroke
				(width 0.1)
				(type default)
			)
			(layer "F.Fab")
		)
		(fp_line
			(start -2.4638 1.0414)
			(end -2.4638 -1.0414)
			(stroke
				(width 0.1)
				(type default)
			)
			(layer "F.Fab")
		)
		(fp_text user "-"
			(at 2.9845 -0.366268 90)
			(unlocked yes)
			(layer "F.SilkS")
			(effects
				(font
					(size 1.905 1.4224)
					(thickness 0.1524)
				)
				(justify left)
			)
		)
		(fp_text user "+"
			(at -3.9624 -0.17145 90)
			(unlocked yes)
			(layer "F.SilkS")
			(effects
				(font
					(size 1.905 1.4224)
					(thickness 0.1524)
				)
				(justify left)
			)
		)
		(fp_text user "-"
			(at 2.9845 -0.366268 90)
			(unlocked yes)
			(layer "F.Fab")
			(effects
				(font
					(size 1.905 1.4224)
					(thickness 0.1524)
				)
				(justify left)
			)
		)
		(fp_text user "+"
			(at -3.9624 -0.17145 90)
			(unlocked yes)
			(layer "F.Fab")
			(effects
				(font
					(size 1.905 1.4224)
					(thickness 0.1524)
				)
				(justify left)
			)
		)
		(pad "1" smd rect
			(at -1.724914 0 90)
			(size 1.1684 1.7526)
			(layers "F.Cu" "F.Mask" "F.Paste")
			(net "P3V3_AUX")
		)
		(pad "2" smd rect
			(at 1.724914 0 90)
			(size 1.1684 1.7526)
			(layers "F.Cu" "F.Mask" "F.Paste")
			(net "P3V3_AUX_JTAG")
		)
	)
	(footprint ""
		(layer "F.Cu")
		(at 357.965756 -231.428798)
		(property "Reference" "R2622"
			(at 0 0 0)
			(layer "F.SilkS")
			(hide yes)
			(effects
				(font
					(size 1.27 1.27)
				)
			)
		)
		(property "Value" ""
			(at 0 0 0)
			(layer "F.Fab")
			(effects
				(font
					(size 1.27 1.27)
				)
			)
		)
		(duplicate_pad_numbers_are_jumpers no)
		(fp_line
			(start -0.7874 -0.4064)
			(end 0.7874 -0.4064)
			(stroke
				(width 0.1524)
				(type default)
			)
			(layer "F.SilkS")
		)
		(fp_line
			(start -0.7874 0.4064)
			(end -0.7874 -0.4064)
			(stroke
				(width 0.1524)
				(type default)
			)
			(layer "F.SilkS")
		)
		(fp_line
			(start 0.7874 -0.4064)
			(end 0.7874 0.4064)
			(stroke
				(width 0.1524)
				(type default)
			)
			(layer "F.SilkS")
		)
		(fp_line
			(start 0.7874 0.4064)
			(end -0.7874 0.4064)
			(stroke
				(width 0.1524)
				(type default)
			)
			(layer "F.SilkS")
		)
		(fp_line
			(start -0.67945 -0.305054)
			(end -0.12065 -0.305054)
			(stroke
				(width 0.1)
				(type default)
			)
			(layer "F.Fab")
		)
		(fp_line
			(start -0.67945 0.3048)
			(end -0.67945 -0.305054)
			(stroke
				(width 0.1)
				(type default)
			)
			(layer "F.Fab")
		)
		(fp_line
			(start -0.12065 -0.305054)
			(end -0.12065 -0.2794)
			(stroke
				(width 0.1)
				(type default)
			)
			(layer "F.Fab")
		)
		(fp_line
			(start -0.12065 -0.2794)
			(end 0.12065 -0.2794)
			(stroke
				(width 0.1)
				(type default)
			)
			(layer "F.Fab")
		)
		(fp_line
			(start -0.12065 0.2794)
			(end -0.12065 0.3048)
			(stroke
				(width 0.1)
				(type default)
			)
			(layer "F.Fab")
		)
		(fp_line
			(start -0.12065 0.3048)
			(end -0.67945 0.3048)
			(stroke
				(width 0.1)
				(type default)
			)
			(layer "F.Fab")
		)
		(fp_line
			(start 0.120396 0.2794)
			(end -0.12065 0.2794)
			(stroke
				(width 0.1)
				(type default)
			)
			(layer "F.Fab")
		)
		(fp_line
			(start 0.120396 0.3048)
			(end 0.120396 0.2794)
			(stroke
				(width 0.1)
				(type default)
			)
			(layer "F.Fab")
		)
		(fp_line
			(start 0.12065 -0.3048)
			(end 0.67945 -0.3048)
			(stroke
				(width 0.1)
				(type default)
			)
			(layer "F.Fab")
		)
		(fp_line
			(start 0.12065 -0.2794)
			(end 0.12065 -0.3048)
			(stroke
				(width 0.1)
				(type default)
			)
			(layer "F.Fab")
		)
		(fp_line
			(start 0.67945 -0.3048)
			(end 0.67945 0.3048)
			(stroke
				(width 0.1)
				(type default)
			)
			(layer "F.Fab")
		)
		(fp_line
			(start 0.67945 0.3048)
			(end 0.120396 0.3048)
			(stroke
				(width 0.1)
				(type default)
			)
			(layer "F.Fab")
		)
		(pad "1" smd circle
			(at -0.40005 0)
			(size 0 0)
			(layers "F.Cu" "F.Mask" "F.Paste")
			(net "FPGA_JTAGENB")
		)
		(pad "2" smd circle
			(at 0.40005 0)
			(size 0 0)
			(layers "F.Cu" "F.Mask" "F.Paste")
			(net "P3V3_AUX")
		)
	)
	(footprint ""
		(layer "F.Cu")
		(at 359.156 -184.15)
		(property "Reference" "R4607"
			(at 0 0 0)
			(layer "F.SilkS")
			(hide yes)
			(effects
				(font
					(size 1.27 1.27)
				)
			)
		)
		(property "Value" ""
			(at 0 0 0)
			(layer "F.Fab")
			(effects
				(font
					(size 1.27 1.27)
				)
			)
		)
		(duplicate_pad_numbers_are_jumpers no)
		(fp_line
			(start -0.7874 -0.4064)
			(end 0.7874 -0.4064)
			(stroke
				(width 0.1524)
				(type default)
			)
			(layer "F.SilkS")
		)
		(fp_line
			(start -0.7874 0.4064)
			(end -0.7874 -0.4064)
			(stroke
				(width 0.1524)
				(type default)
			)
			(layer "F.SilkS")
		)
		(fp_line
			(start 0.7874 -0.4064)
			(end 0.7874 0.4064)
			(stroke
				(width 0.1524)
				(type default)
			)
			(layer "F.SilkS")
		)
		(fp_line
			(start 0.7874 0.4064)
			(end -0.7874 0.4064)
			(stroke
				(width 0.1524)
				(type default)
			)
			(layer "F.SilkS")
		)
		(fp_line
			(start -0.67945 -0.305054)
			(end -0.12065 -0.305054)
			(stroke
				(width 0.1)
				(type default)
			)
			(layer "F.Fab")
		)
		(fp_line
			(start -0.67945 0.3048)
			(end -0.67945 -0.305054)
			(stroke
				(width 0.1)
				(type default)
			)
			(layer "F.Fab")
		)
		(fp_line
			(start -0.12065 -0.305054)
			(end -0.12065 -0.2794)
			(stroke
				(width 0.1)
				(type default)
			)
			(layer "F.Fab")
		)
		(fp_line
			(start -0.12065 -0.2794)
			(end 0.12065 -0.2794)
			(stroke
				(width 0.1)
				(type default)
			)
			(layer "F.Fab")
		)
		(fp_line
			(start -0.12065 0.2794)
			(end -0.12065 0.3048)
			(stroke
				(width 0.1)
				(type default)
			)
			(layer "F.Fab")
		)
		(fp_line
			(start -0.12065 0.3048)
			(end -0.67945 0.3048)
			(stroke
				(width 0.1)
				(type default)
			)
			(layer "F.Fab")
		)
		(fp_line
			(start 0.120396 0.2794)
			(end -0.12065 0.2794)
			(stroke
				(width 0.1)
				(type default)
			)
			(layer "F.Fab")
		)
		(fp_line
			(start 0.120396 0.3048)
			(end 0.120396 0.2794)
			(stroke
				(width 0.1)
				(type default)
			)
			(layer "F.Fab")
		)
		(fp_line
			(start 0.12065 -0.3048)
			(end 0.67945 -0.3048)
			(stroke
				(width 0.1)
				(type default)
			)
			(layer "F.Fab")
		)
		(fp_line
			(start 0.12065 -0.2794)
			(end 0.12065 -0.3048)
			(stroke
				(width 0.1)
				(type default)
			)
			(layer "F.Fab")
		)
		(fp_line
			(start 0.67945 -0.3048)
			(end 0.67945 0.3048)
			(stroke
				(width 0.1)
				(type default)
			)
			(layer "F.Fab")
		)
		(fp_line
			(start 0.67945 0.3048)
			(end 0.120396 0.3048)
			(stroke
				(width 0.1)
				(type default)
			)
			(layer "F.Fab")
		)
		(pad "1" smd circle
			(at -0.40005 0)
			(size 0 0)
			(layers "F.Cu" "F.Mask" "F.Paste")
			(net "P3V3_AUX")
		)
		(pad "2" smd circle
			(at 0.40005 0)
			(size 0 0)
			(layers "F.Cu" "F.Mask" "F.Paste")
			(net "RST_PEX_SSD3_PERST_R_N")
		)
	)
	(footprint ""
		(layer "F.Cu")
		(at 419.510972 -356.244906 90)
		(property "Reference" "C2450"
			(at 0 0 90)
			(layer "F.SilkS")
			(hide yes)
			(effects
				(font
					(size 1.27 1.27)
				)
			)
		)
		(property "Value" ""
			(at 0 0 90)
			(layer "F.Fab")
			(effects
				(font
					(size 1.27 1.27)
				)
			)
		)
		(duplicate_pad_numbers_are_jumpers no)
		(fp_line
			(start 0.299974 -0.150114)
			(end 0.299974 0.150114)
			(stroke
				(width 0.1)
				(type default)
			)
			(layer "F.Fab")
		)
		(fp_line
			(start -0.299974 -0.150114)
			(end 0.299974 -0.150114)
			(stroke
				(width 0.1)
				(type default)
			)
			(layer "F.Fab")
		)
		(fp_line
			(start 0.299974 0.150114)
			(end -0.299974 0.150114)
			(stroke
				(width 0.1)
				(type default)
			)
			(layer "F.Fab")
		)
		(fp_line
			(start -0.299974 0.150114)
			(end -0.299974 -0.150114)
			(stroke
				(width 0.1)
				(type default)
			)
			(layer "F.Fab")
		)
		(pad "1" smd rect
			(at -0.2667 0 90)
			(size 0.3048 0.381)
			(layers "F.Cu" "F.Mask" "F.Paste")
			(net "P5E_PEX3_STN4_TX_DN<74>")
		)
		(pad "2" smd rect
			(at 0.2667 0 90)
			(size 0.3048 0.381)
			(layers "F.Cu" "F.Mask" "F.Paste")
			(net "P5E_PEX3_STN4_TX_C_DN<74>")
		)
	)
	(footprint ""
		(layer "F.Cu")
		(at 150.602442 -252.356874 -90)
		(property "Reference" "R1300"
			(at 0 0 270)
			(layer "F.SilkS")
			(hide yes)
			(effects
				(font
					(size 1.27 1.27)
				)
			)
		)
		(property "Value" ""
			(at 0 0 270)
			(layer "F.Fab")
			(effects
				(font
					(size 1.27 1.27)
				)
			)
		)
		(duplicate_pad_numbers_are_jumpers no)
		(fp_line
			(start -0.7874 0.4064)
			(end -0.7874 -0.4064)
			(stroke
				(width 0.1524)
				(type default)
			)
			(layer "F.SilkS")
		)
		(fp_line
			(start 0.7874 0.4064)
			(end -0.7874 0.4064)
			(stroke
				(width 0.1524)
				(type default)
			)
			(layer "F.SilkS")
		)
		(fp_line
			(start -0.7874 -0.4064)
			(end 0.7874 -0.4064)
			(stroke
				(width 0.1524)
				(type default)
			)
			(layer "F.SilkS")
		)
		(fp_line
			(start 0.7874 -0.4064)
			(end 0.7874 0.4064)
			(stroke
				(width 0.1524)
				(type default)
			)
			(layer "F.SilkS")
		)
		(fp_line
			(start -0.67945 0.3048)
			(end -0.67945 -0.305054)
			(stroke
				(width 0.1)
				(type default)
			)
			(layer "F.Fab")
		)
		(fp_line
			(start -0.12065 0.3048)
			(end -0.67945 0.3048)
			(stroke
				(width 0.1)
				(type default)
			)
			(layer "F.Fab")
		)
		(fp_line
			(start 0.120396 0.3048)
			(end 0.120396 0.2794)
			(stroke
				(width 0.1)
				(type default)
			)
			(layer "F.Fab")
		)
		(fp_line
			(start 0.67945 0.3048)
			(end 0.120396 0.3048)
			(stroke
				(width 0.1)
				(type default)
			)
			(layer "F.Fab")
		)
		(fp_line
			(start -0.12065 0.2794)
			(end -0.12065 0.3048)
			(stroke
				(width 0.1)
				(type default)
			)
			(layer "F.Fab")
		)
		(fp_line
			(start 0.120396 0.2794)
			(end -0.12065 0.2794)
			(stroke
				(width 0.1)
				(type default)
			)
			(layer "F.Fab")
		)
		(fp_line
			(start -0.12065 -0.2794)
			(end 0.12065 -0.2794)
			(stroke
				(width 0.1)
				(type default)
			)
			(layer "F.Fab")
		)
		(fp_line
			(start 0.12065 -0.2794)
			(end 0.12065 -0.3048)
			(stroke
				(width 0.1)
				(type default)
			)
			(layer "F.Fab")
		)
		(fp_line
			(start 0.12065 -0.3048)
			(end 0.67945 -0.3048)
			(stroke
				(width 0.1)
				(type default)
			)
			(layer "F.Fab")
		)
		(fp_line
			(start 0.67945 -0.3048)
			(end 0.67945 0.3048)
			(stroke
				(width 0.1)
				(type default)
			)
			(layer "F.Fab")
		)
		(fp_line
			(start -0.67945 -0.305054)
			(end -0.12065 -0.305054)
			(stroke
				(width 0.1)
				(type default)
			)
			(layer "F.Fab")
		)
		(fp_line
			(start -0.12065 -0.305054)
			(end -0.12065 -0.2794)
			(stroke
				(width 0.1)
				(type default)
			)
			(layer "F.Fab")
		)
		(pad "1" smd circle
			(at -0.40005 0 270)
			(size 0 0)
			(layers "F.Cu" "F.Mask" "F.Paste")
			(net "GND")
		)
		(pad "2" smd circle
			(at 0.40005 0 270)
			(size 0 0)
			(layers "F.Cu" "F.Mask" "F.Paste")
			(net "PEX1_MODE_SEL11")
		)
	)
	(footprint ""
		(layer "F.Cu")
		(at 31.742888 -350.098614 90)
		(property "Reference" "C179"
			(at 0 0 90)
			(layer "F.SilkS")
			(hide yes)
			(effects
				(font
					(size 1.27 1.27)
				)
			)
		)
		(property "Value" ""
			(at 0 0 90)
			(layer "F.Fab")
			(effects
				(font
					(size 1.27 1.27)
				)
			)
		)
		(duplicate_pad_numbers_are_jumpers no)
		(fp_line
			(start 0.299974 -0.150114)
			(end 0.299974 0.150114)
			(stroke
				(width 0.1)
				(type default)
			)
			(layer "F.Fab")
		)
		(fp_line
			(start -0.299974 -0.150114)
			(end 0.299974 -0.150114)
			(stroke
				(width 0.1)
				(type default)
			)
			(layer "F.Fab")
		)
		(fp_line
			(start 0.299974 0.150114)
			(end -0.299974 0.150114)
			(stroke
				(width 0.1)
				(type default)
			)
			(layer "F.Fab")
		)
		(fp_line
			(start -0.299974 0.150114)
			(end -0.299974 -0.150114)
			(stroke
				(width 0.1)
				(type default)
			)
			(layer "F.Fab")
		)
		(pad "1" smd rect
			(at -0.2667 0 90)
			(size 0.3048 0.381)
			(layers "F.Cu" "F.Mask" "F.Paste")
			(net "P5E_PEX0_STN7_TX_DP<118>")
		)
		(pad "2" smd rect
			(at 0.2667 0 90)
			(size 0.3048 0.381)
			(layers "F.Cu" "F.Mask" "F.Paste")
			(net "P5E_PEX0_STN7_TX_C_DP<118>")
		)
	)
	(footprint ""
		(layer "F.Cu")
		(at 239.70869 -214.923878 90)
		(property "Reference" "C194"
			(at 0 0 90)
			(layer "F.SilkS")
			(hide yes)
			(effects
				(font
					(size 1.27 1.27)
				)
			)
		)
		(property "Value" ""
			(at 0 0 90)
			(layer "F.Fab")
			(effects
				(font
					(size 1.27 1.27)
				)
			)
		)
		(duplicate_pad_numbers_are_jumpers no)
		(fp_line
			(start 0.7874 -0.4064)
			(end 0.7874 0.4064)
			(stroke
				(width 0.1524)
				(type default)
			)
			(layer "F.SilkS")
		)
		(fp_line
			(start -0.7874 -0.4064)
			(end 0.7874 -0.4064)
			(stroke
				(width 0.1524)
				(type default)
			)
			(layer "F.SilkS")
		)
		(fp_line
			(start 0.7874 0.4064)
			(end -0.7874 0.4064)
			(stroke
				(width 0.1524)
				(type default)
			)
			(layer "F.SilkS")
		)
		(fp_line
			(start -0.7874 0.4064)
			(end -0.7874 -0.4064)
			(stroke
				(width 0.1524)
				(type default)
			)
			(layer "F.SilkS")
		)
		(fp_line
			(start -0.12065 -0.305054)
			(end -0.12065 -0.2794)
			(stroke
				(width 0.1)
				(type default)
			)
			(layer "F.Fab")
		)
		(fp_line
			(start -0.67945 -0.305054)
			(end -0.12065 -0.305054)
			(stroke
				(width 0.1)
				(type default)
			)
			(layer "F.Fab")
		)
		(fp_line
			(start 0.67945 -0.3048)
			(end 0.67945 0.3048)
			(stroke
				(width 0.1)
				(type default)
			)
			(layer "F.Fab")
		)
		(fp_line
			(start 0.12065 -0.3048)
			(end 0.67945 -0.3048)
			(stroke
				(width 0.1)
				(type default)
			)
			(layer "F.Fab")
		)
		(fp_line
			(start 0.12065 -0.2794)
			(end 0.12065 -0.3048)
			(stroke
				(width 0.1)
				(type default)
			)
			(layer "F.Fab")
		)
		(fp_line
			(start -0.12065 -0.2794)
			(end 0.12065 -0.2794)
			(stroke
				(width 0.1)
				(type default)
			)
			(layer "F.Fab")
		)
		(fp_line
			(start 0.120396 0.2794)
			(end -0.12065 0.2794)
			(stroke
				(width 0.1)
				(type default)
			)
			(layer "F.Fab")
		)
		(fp_line
			(start -0.12065 0.2794)
			(end -0.12065 0.3048)
			(stroke
				(width 0.1)
				(type default)
			)
			(layer "F.Fab")
		)
		(fp_line
			(start 0.67945 0.3048)
			(end 0.120396 0.3048)
			(stroke
				(width 0.1)
				(type default)
			)
			(layer "F.Fab")
		)
		(fp_line
			(start 0.120396 0.3048)
			(end 0.120396 0.2794)
			(stroke
				(width 0.1)
				(type default)
			)
			(layer "F.Fab")
		)
		(fp_line
			(start -0.12065 0.3048)
			(end -0.67945 0.3048)
			(stroke
				(width 0.1)
				(type default)
			)
			(layer "F.Fab")
		)
		(fp_line
			(start -0.67945 0.3048)
			(end -0.67945 -0.305054)
			(stroke
				(width 0.1)
				(type default)
			)
			(layer "F.Fab")
		)
		(pad "1" smd circle
			(at -0.40005 0 90)
			(size 0 0)
			(layers "F.Cu" "F.Mask" "F.Paste")
			(net "P3V3_AUX_SCALED")
		)
		(pad "2" smd circle
			(at 0.40005 0 90)
			(size 0 0)
			(layers "F.Cu" "F.Mask" "F.Paste")
			(net "GND")
		)
	)
	(footprint ""
		(layer "F.Cu")
		(at 301.992284 -31.825184 180)
		(property "Reference" "C506"
			(at 0 0 180)
			(layer "F.SilkS")
			(hide yes)
			(effects
				(font
					(size 1.27 1.27)
				)
			)
		)
		(property "Value" ""
			(at 0 0 180)
			(layer "F.Fab")
			(effects
				(font
					(size 1.27 1.27)
				)
			)
		)
		(duplicate_pad_numbers_are_jumpers no)
		(fp_line
			(start 0.299974 0.150114)
			(end -0.299974 0.150114)
			(stroke
				(width 0.1)
				(type default)
			)
			(layer "F.Fab")
		)
		(fp_line
			(start 0.299974 -0.150114)
			(end 0.299974 0.150114)
			(stroke
				(width 0.1)
				(type default)
			)
			(layer "F.Fab")
		)
		(fp_line
			(start -0.299974 0.150114)
			(end -0.299974 -0.150114)
			(stroke
				(width 0.1)
				(type default)
			)
			(layer "F.Fab")
		)
		(fp_line
			(start -0.299974 -0.150114)
			(end 0.299974 -0.150114)
			(stroke
				(width 0.1)
				(type default)
			)
			(layer "F.Fab")
		)
		(pad "1" smd rect
			(at -0.2667 0 180)
			(size 0.3048 0.381)
			(layers "F.Cu" "F.Mask" "F.Paste")
			(net "P5E_PEX2_STN2_TX_DN<38>")
		)
		(pad "2" smd rect
			(at 0.2667 0 180)
			(size 0.3048 0.381)
			(layers "F.Cu" "F.Mask" "F.Paste")
			(net "P5E_PEX2_STN2_TX_C_DN<38>")
		)
	)
)
